# BASEBOARD_FAB2 (Tioga Pass) — schematic netlist excerpt (pin names and nets, part order shuffled) for the footprints in the layout excerpt that follows; sources: Cadence DE-HDL packaged netlist, KiCad conversion of Wiwynn_Tioga_Pass_MB.brd

R9U7  RES  0.0 5% CHIP  pkg 0402  page 223 : A = FM_PVDDQ_GHJ_EN ; B = VR_PVDDQ_GHJ_VREN
C25W75  CAP  12.0PF 50V 5% COG  pkg 0402LF  page 252 : A = V_IO_B_J ; B = GND

(kicad_pcb
	(version 20260206)
	(generator "pcbnew")
	(generator_version "10.0")
	(general
		(thickness 1.6)
		(legacy_teardrops no)
	)
	(paper "A4")
	(title_block
		(title "Wiwynn_Tioga_Pass_MB.brd")
		(comment 1 "Tioga Pass / footprints 3534-3535 of 4770")
	)
	(layers
		(0 "F.Cu" signal "TOP")
		(4 "In1.Cu" signal "L2GND")
		(6 "In2.Cu" signal "L3")
		(8 "In3.Cu" signal "L4GND")
		(10 "In4.Cu" signal "L5")
		(12 "In5.Cu" signal "L6GND")
		(14 "In6.Cu" signal "L7VCC")
		(16 "In7.Cu" signal "L8VCC")
		(18 "In8.Cu" signal "L9GND")
		(20 "In9.Cu" signal "L10")
		(22 "In10.Cu" signal "L11GND")
		(24 "In11.Cu" signal "L12")
		(26 "In12.Cu" signal "L13GND")
		(2 "B.Cu" signal "BOTTOM")
		(9 "F.Adhes" user "F.Adhesive")
		(11 "B.Adhes" user "B.Adhesive")
		(13 "F.Paste" user "Package Geometry/Pastemask Top")
		(15 "B.Paste" user "Package Geometry/Pastemask Bottom")
		(5 "F.SilkS" user "Ref Des/Silkscreen Top")
		(7 "B.SilkS" user "Ref Des/Silkscreen Bottom")
		(1 "F.Mask" user "Board Geometry/Soldermask Top")
		(3 "B.Mask" user "Board Geometry/Soldermask Bottom")
		(17 "Dwgs.User" user "User.Drawings")
		(19 "Cmts.User" user "User.Comments")
		(21 "Eco1.User" user "User.Eco1")
		(23 "Eco2.User" user "User.Eco2")
		(25 "Edge.Cuts" user "Board Geometry/Outline")
		(27 "Margin" user)
		(31 "F.CrtYd" user "Package Geometry/Place Bound Top")
		(29 "B.CrtYd" user "Package Geometry/Place Bound Bottom")
		(35 "F.Fab" user "Ref Des/Assembly Top")
		(33 "B.Fab" user "Ref Des/Assembly Bottom")
	)
	(footprint ""
		(layer "B.Cu")
		(at 420.624 -22.352)
		(property "Reference" "C25W75"
			(at 0.8382 -0.67818 0)
			(unlocked yes)
			(layer "B.SilkS")
			(effects
				(font
					(size 0.4064 0.254)
					(thickness 0.1524)
				)
				(justify left mirror)
			)
		)
		(property "Value" ""
			(at 0 0 0)
			(layer "B.Fab")
			(effects
				(font
					(size 1.27 1.27)
				)
				(justify mirror)
			)
		)
		(duplicate_pad_numbers_are_jumpers no)
		(fp_poly
			(pts
				(xy -0.3048 -0.1016) (xy -0.3048 0.9906) (xy 0.3048 0.9906) (xy 0.3048 -0.1016)
			)
			(stroke
				(width 0)
				(type default)
			)
			(fill no)
			(layer "B.CrtYd")
		)
		(fp_line
			(start -0.3048 -0.1016)
			(end 0.3048 -0.1016)
			(stroke
				(width 0.1)
				(type default)
			)
			(layer "B.Fab")
		)
		(fp_line
			(start -0.3048 0.9906)
			(end -0.3048 -0.1016)
			(stroke
				(width 0.1)
				(type default)
			)
			(layer "B.Fab")
		)
		(fp_line
			(start 0.3048 -0.1016)
			(end 0.3048 0.9906)
			(stroke
				(width 0.1)
				(type default)
			)
			(layer "B.Fab")
		)
		(fp_line
			(start 0.3048 0.9906)
			(end -0.3048 0.9906)
			(stroke
				(width 0.1)
				(type default)
			)
			(layer "B.Fab")
		)
		(pad "1" smd rect
			(at 0 0 180)
			(size 0.508 0.508)
			(layers "B.Cu" "B.Mask" "B.Paste")
			(net "V_IO_B_J")
		)
		(pad "2" smd rect
			(at 0 0.889 180)
			(size 0.508 0.508)
			(layers "B.Cu" "B.Mask" "B.Paste")
			(net "GND")
		)
		(zone
			(layer "B.Cu")
			(hatch none 0.5)
			(connect_pads
				(clearance 0)
			)
			(min_thickness 0.25)
			(keepout
				(tracks allowed)
				(vias not_allowed)
				(pads allowed)
				(copperpour not_allowed)
				(footprints allowed)
			)
			(placement
				(enabled no)
				(sheetname "")
			)
			(fill
				(thermal_gap 0.5)
				(thermal_bridge_width 0.5)
				(island_removal_mode 0)
			)
			(polygon
				(pts
					(xy 420.878 -22.098) (xy 420.37 -22.098) (xy 420.37 -21.717) (xy 420.878 -21.717)
				)
			)
		)
		(zone
			(layer "B.Cu")
			(hatch none 0.5)
			(connect_pads
				(clearance 0)
			)
			(min_thickness 0.25)
			(keepout
				(tracks not_allowed)
				(vias allowed)
				(pads allowed)
				(copperpour not_allowed)
				(footprints allowed)
			)
			(placement
				(enabled no)
				(sheetname "")
			)
			(fill
				(thermal_gap 0.5)
				(thermal_bridge_width 0.5)
				(island_removal_mode 0)
			)
			(polygon
				(pts
					(xy 420.878 -21.717) (xy 420.37 -21.717) (xy 420.37 -22.098) (xy 420.878 -22.098)
				)
			)
		)
	)
	(footprint ""
		(layer "B.Cu")
		(at 13.923264 2.985516 90)
		(property "Reference" "R9U7"
			(at 0 0 90)
			(layer "B.SilkS")
			(hide yes)
			(effects
				(font
					(size 1.27 1.27)
				)
				(justify mirror)
			)
		)
		(property "Value" ""
			(at 0 0 90)
			(layer "B.Fab")
			(effects
				(font
					(size 1.27 1.27)
				)
				(justify mirror)
			)
		)
		(duplicate_pad_numbers_are_jumpers no)
		(fp_poly
			(pts
				(xy 0.2794 -0.1016) (xy -0.2794 -0.1016) (xy -0.2794 0.9906) (xy 0.2794 0.9906)
			)
			(stroke
				(width 0)
				(type default)
			)
			(fill no)
			(layer "B.CrtYd")
		)
		(fp_line
			(start 0.2794 -0.1016)
			(end 0.2794 0.9906)
			(stroke
				(width 0.1)
				(type default)
			)
			(layer "B.Fab")
		)
		(fp_line
			(start -0.2794 -0.1016)
			(end 0.2794 -0.1016)
			(stroke
				(width 0.1)
				(type default)
			)
			(layer "B.Fab")
		)
		(fp_line
			(start 0.2794 0.9906)
			(end -0.2794 0.9906)
			(stroke
				(width 0.1)
				(type default)
			)
			(layer "B.Fab")
		)
		(fp_line
			(start -0.2794 0.9906)
			(end -0.2794 -0.1016)
			(stroke
				(width 0.1)
				(type default)
			)
			(layer "B.Fab")
		)
		(pad "1" smd rect
			(at 0 0 270)
			(size 0.508 0.508)
			(layers "B.Cu" "B.Mask" "B.Paste")
			(net "FM_PVDDQ_GHJ_EN")
		)
		(pad "2" smd rect
			(at 0 0.889 270)
			(size 0.508 0.508)
			(layers "B.Cu" "B.Mask" "B.Paste")
			(net "VR_PVDDQ_GHJ_VREN")
		)
		(zone
			(layer "B.Cu")
			(hatch none 0.5)
			(connect_pads
				(clearance 0)
			)
			(min_thickness 0.25)
			(keepout
				(tracks allowed)
				(vias not_allowed)
				(pads allowed)
				(copperpour not_allowed)
				(footprints allowed)
			)
			(placement
				(enabled no)
				(sheetname "")
			)
			(fill
				(thermal_gap 0.5)
				(thermal_bridge_width 0.5)
				(island_removal_mode 0)
			)
			(polygon
				(pts
					(xy 14.177264 2.731516) (xy 14.177264 3.239516) (xy 14.558264 3.239516) (xy 14.558264 2.731516)
				)
			)
		)
		(zone
			(layer "B.Cu")
			(hatch none 0.5)
			(connect_pads
				(clearance 0)
			)
			(min_thickness 0.25)
			(keepout
				(tracks not_allowed)
				(vias allowed)
				(pads allowed)
				(copperpour not_allowed)
				(footprints allowed)
			)
			(placement
				(enabled no)
				(sheetname "")
			)
			(fill
				(thermal_gap 0.5)
				(thermal_bridge_width 0.5)
				(island_removal_mode 0)
			)
			(polygon
				(pts
					(xy 14.558264 2.731516) (xy 14.558264 3.239516) (xy 14.177264 3.239516) (xy 14.177264 2.731516)
				)
			)
		)
	)
)
